FILE_TYPE = CONNECTIVITY;
{Allegro Design Entry HDL 17.2-2016 S081 (4005846) 1/11/2022}
"PAGE_NUMBER" = 6;
0"NC";
END.
